(kicad_pcb
	(version 20260206)
	(generator "pcbnew")
	(generator_version "10.0")
	(general
		(thickness 1.6)
		(legacy_teardrops no)
	)
	(paper "A4")
	(title_block
		(title "04192023_DAF0TMB3IC0_F0TG_MB_C_brd_V02_OCP.brd")
		(comment 1 "Grand Teton / footprints 1071-1077 of 8354")
	)
	(layers
		(0 "F.Cu" signal "TOP")
		(4 "In1.Cu" signal "GND")
		(6 "In2.Cu" signal "IN1")
		(8 "In3.Cu" signal "GND1")
		(10 "In4.Cu" signal "IN2")
		(12 "In5.Cu" signal "GND2")
		(14 "In6.Cu" signal "IN3")
		(16 "In7.Cu" signal "GND3")
		(18 "In8.Cu" signal "VCC")
		(20 "In9.Cu" signal "VCC1")
		(22 "In10.Cu" signal "GND4")
		(24 "In11.Cu" signal "IN4")
		(26 "In12.Cu" signal "GND5")
		(28 "In13.Cu" signal "IN5")
		(30 "In14.Cu" signal "GND6")
		(32 "In15.Cu" signal "IN6")
		(34 "In16.Cu" signal "GND7")
		(2 "B.Cu" signal "BOTTOM")
		(9 "F.Adhes" user "F.Adhesive")
		(11 "B.Adhes" user "B.Adhesive")
		(13 "F.Paste" user "Package Geometry/Pastemask Top")
		(15 "B.Paste" user "Package Geometry/Pastemask Bottom")
		(5 "F.SilkS" user "Ref Des/Silkscreen Top")
		(7 "B.SilkS" user "Ref Des/Silkscreen Bottom")
		(1 "F.Mask" user "Board Geometry/Soldermask Top")
		(3 "B.Mask" user "Board Geometry/Soldermask Bottom")
		(17 "Dwgs.User" user "User.Drawings")
		(19 "Cmts.User" user "User.Comments")
		(21 "Eco1.User" user "User.Eco1")
		(23 "Eco2.User" user "User.Eco2")
		(25 "Edge.Cuts" user "Board Geometry/Outline")
		(27 "Margin" user)
		(31 "F.CrtYd" user "Package Geometry/Place Bound Top")
		(29 "B.CrtYd" user "Package Geometry/Place Bound Bottom")
		(35 "F.Fab" user "Ref Des/Assembly Top")
		(33 "B.Fab" user "Ref Des/Assembly Bottom")
	)
	(footprint ""
		(layer "F.Cu")
		(at 150.814532 -106.73207 -90)
		(property "Reference" "R1134"
			(at 0 0 270)
			(layer "F.SilkS")
			(hide yes)
			(effects
				(font
					(size 1.27 1.27)
				)
			)
		)
		(property "Value" ""
			(at 0 0 270)
			(layer "F.Fab")
			(effects
				(font
					(size 1.27 1.27)
				)
			)
		)
		(duplicate_pad_numbers_are_jumpers no)
		(fp_line
			(start -0.7874 0.4064)
			(end -0.7874 -0.4064)
			(stroke
				(width 0.1524)
				(type default)
			)
			(layer "F.SilkS")
		)
		(fp_line
			(start 0.7874 0.4064)
			(end -0.7874 0.4064)
			(stroke
				(width 0.1524)
				(type default)
			)
			(layer "F.SilkS")
		)
		(fp_line
			(start -0.7874 -0.4064)
			(end 0.7874 -0.4064)
			(stroke
				(width 0.1524)
				(type default)
			)
			(layer "F.SilkS")
		)
		(fp_line
			(start 0.7874 -0.4064)
			(end 0.7874 0.4064)
			(stroke
				(width 0.1524)
				(type default)
			)
			(layer "F.SilkS")
		)
		(fp_line
			(start -0.67945 0.3048)
			(end -0.67945 -0.305054)
			(stroke
				(width 0.1)
				(type default)
			)
			(layer "F.Fab")
		)
		(fp_line
			(start -0.12065 0.3048)
			(end -0.67945 0.3048)
			(stroke
				(width 0.1)
				(type default)
			)
			(layer "F.Fab")
		)
		(fp_line
			(start 0.120396 0.3048)
			(end 0.120396 0.2794)
			(stroke
				(width 0.1)
				(type default)
			)
			(layer "F.Fab")
		)
		(fp_line
			(start 0.67945 0.3048)
			(end 0.120396 0.3048)
			(stroke
				(width 0.1)
				(type default)
			)
			(layer "F.Fab")
		)
		(fp_line
			(start -0.12065 0.2794)
			(end -0.12065 0.3048)
			(stroke
				(width 0.1)
				(type default)
			)
			(layer "F.Fab")
		)
		(fp_line
			(start 0.120396 0.2794)
			(end -0.12065 0.2794)
			(stroke
				(width 0.1)
				(type default)
			)
			(layer "F.Fab")
		)
		(fp_line
			(start -0.12065 -0.2794)
			(end 0.12065 -0.2794)
			(stroke
				(width 0.1)
				(type default)
			)
			(layer "F.Fab")
		)
		(fp_line
			(start 0.12065 -0.2794)
			(end 0.12065 -0.3048)
			(stroke
				(width 0.1)
				(type default)
			)
			(layer "F.Fab")
		)
		(fp_line
			(start 0.12065 -0.3048)
			(end 0.67945 -0.3048)
			(stroke
				(width 0.1)
				(type default)
			)
			(layer "F.Fab")
		)
		(fp_line
			(start 0.67945 -0.3048)
			(end 0.67945 0.3048)
			(stroke
				(width 0.1)
				(type default)
			)
			(layer "F.Fab")
		)
		(fp_line
			(start -0.67945 -0.305054)
			(end -0.12065 -0.305054)
			(stroke
				(width 0.1)
				(type default)
			)
			(layer "F.Fab")
		)
		(fp_line
			(start -0.12065 -0.305054)
			(end -0.12065 -0.2794)
			(stroke
				(width 0.1)
				(type default)
			)
			(layer "F.Fab")
		)
		(pad "1" smd circle
			(at -0.40005 0 270)
			(size 0 0)
			(layers "F.Cu" "F.Mask" "F.Paste")
			(net "P12V_OCP_SFF_BUF_EN")
		)
		(pad "2" smd circle
			(at 0.40005 0 270)
			(size 0 0)
			(layers "F.Cu" "F.Mask" "F.Paste")
			(net "P12V_OCP_SFF_BUF_EN_R")
		)
	)
	(footprint ""
		(layer "F.Cu")
		(at 58.08345 -143.664686 -90)
		(property "Reference" "PR402"
			(at 0 0 270)
			(layer "F.SilkS")
			(hide yes)
			(effects
				(font
					(size 1.27 1.27)
				)
			)
		)
		(property "Value" ""
			(at 0 0 270)
			(layer "F.Fab")
			(effects
				(font
					(size 1.27 1.27)
				)
			)
		)
		(duplicate_pad_numbers_are_jumpers no)
		(fp_line
			(start -0.7874 0.4064)
			(end -0.7874 -0.4064)
			(stroke
				(width 0.1524)
				(type default)
			)
			(layer "F.SilkS")
		)
		(fp_line
			(start 0.7874 0.4064)
			(end -0.7874 0.4064)
			(stroke
				(width 0.1524)
				(type default)
			)
			(layer "F.SilkS")
		)
		(fp_line
			(start -0.7874 -0.4064)
			(end 0.7874 -0.4064)
			(stroke
				(width 0.1524)
				(type default)
			)
			(layer "F.SilkS")
		)
		(fp_line
			(start 0.7874 -0.4064)
			(end 0.7874 0.4064)
			(stroke
				(width 0.1524)
				(type default)
			)
			(layer "F.SilkS")
		)
		(fp_line
			(start -0.67945 0.3048)
			(end -0.67945 -0.305054)
			(stroke
				(width 0.1)
				(type default)
			)
			(layer "F.Fab")
		)
		(fp_line
			(start -0.12065 0.3048)
			(end -0.67945 0.3048)
			(stroke
				(width 0.1)
				(type default)
			)
			(layer "F.Fab")
		)
		(fp_line
			(start 0.120396 0.3048)
			(end 0.120396 0.2794)
			(stroke
				(width 0.1)
				(type default)
			)
			(layer "F.Fab")
		)
		(fp_line
			(start 0.67945 0.3048)
			(end 0.120396 0.3048)
			(stroke
				(width 0.1)
				(type default)
			)
			(layer "F.Fab")
		)
		(fp_line
			(start -0.12065 0.2794)
			(end -0.12065 0.3048)
			(stroke
				(width 0.1)
				(type default)
			)
			(layer "F.Fab")
		)
		(fp_line
			(start 0.120396 0.2794)
			(end -0.12065 0.2794)
			(stroke
				(width 0.1)
				(type default)
			)
			(layer "F.Fab")
		)
		(fp_line
			(start -0.12065 -0.2794)
			(end 0.12065 -0.2794)
			(stroke
				(width 0.1)
				(type default)
			)
			(layer "F.Fab")
		)
		(fp_line
			(start 0.12065 -0.2794)
			(end 0.12065 -0.3048)
			(stroke
				(width 0.1)
				(type default)
			)
			(layer "F.Fab")
		)
		(fp_line
			(start 0.12065 -0.3048)
			(end 0.67945 -0.3048)
			(stroke
				(width 0.1)
				(type default)
			)
			(layer "F.Fab")
		)
		(fp_line
			(start 0.67945 -0.3048)
			(end 0.67945 0.3048)
			(stroke
				(width 0.1)
				(type default)
			)
			(layer "F.Fab")
		)
		(fp_line
			(start -0.67945 -0.305054)
			(end -0.12065 -0.305054)
			(stroke
				(width 0.1)
				(type default)
			)
			(layer "F.Fab")
		)
		(fp_line
			(start -0.12065 -0.305054)
			(end -0.12065 -0.2794)
			(stroke
				(width 0.1)
				(type default)
			)
			(layer "F.Fab")
		)
		(pad "1" smd circle
			(at -0.40005 0 270)
			(size 0 0)
			(layers "F.Cu" "F.Mask" "F.Paste")
			(net "PVDD18_S5_P1")
		)
		(pad "2" smd circle
			(at 0.40005 0 270)
			(size 0 0)
			(layers "F.Cu" "F.Mask" "F.Paste")
			(net "PVDD18_S5_P1_FB_RC")
		)
	)
	(footprint ""
		(layer "F.Cu")
		(at 462.20507 -40.226488 -90)
		(property "Reference" "R4068"
			(at 0 0 270)
			(layer "F.SilkS")
			(hide yes)
			(effects
				(font
					(size 1.27 1.27)
				)
			)
		)
		(property "Value" ""
			(at 0 0 270)
			(layer "F.Fab")
			(effects
				(font
					(size 1.27 1.27)
				)
			)
		)
		(duplicate_pad_numbers_are_jumpers no)
		(fp_line
			(start -0.7874 0.4064)
			(end -0.7874 -0.4064)
			(stroke
				(width 0.1524)
				(type default)
			)
			(layer "F.SilkS")
		)
		(fp_line
			(start 0.7874 0.4064)
			(end -0.7874 0.4064)
			(stroke
				(width 0.1524)
				(type default)
			)
			(layer "F.SilkS")
		)
		(fp_line
			(start -0.7874 -0.4064)
			(end 0.7874 -0.4064)
			(stroke
				(width 0.1524)
				(type default)
			)
			(layer "F.SilkS")
		)
		(fp_line
			(start 0.7874 -0.4064)
			(end 0.7874 0.4064)
			(stroke
				(width 0.1524)
				(type default)
			)
			(layer "F.SilkS")
		)
		(fp_line
			(start -0.67945 0.3048)
			(end -0.67945 -0.305054)
			(stroke
				(width 0.1)
				(type default)
			)
			(layer "F.Fab")
		)
		(fp_line
			(start -0.12065 0.3048)
			(end -0.67945 0.3048)
			(stroke
				(width 0.1)
				(type default)
			)
			(layer "F.Fab")
		)
		(fp_line
			(start 0.120396 0.3048)
			(end 0.120396 0.2794)
			(stroke
				(width 0.1)
				(type default)
			)
			(layer "F.Fab")
		)
		(fp_line
			(start 0.67945 0.3048)
			(end 0.120396 0.3048)
			(stroke
				(width 0.1)
				(type default)
			)
			(layer "F.Fab")
		)
		(fp_line
			(start -0.12065 0.2794)
			(end -0.12065 0.3048)
			(stroke
				(width 0.1)
				(type default)
			)
			(layer "F.Fab")
		)
		(fp_line
			(start 0.120396 0.2794)
			(end -0.12065 0.2794)
			(stroke
				(width 0.1)
				(type default)
			)
			(layer "F.Fab")
		)
		(fp_line
			(start -0.12065 -0.2794)
			(end 0.12065 -0.2794)
			(stroke
				(width 0.1)
				(type default)
			)
			(layer "F.Fab")
		)
		(fp_line
			(start 0.12065 -0.2794)
			(end 0.12065 -0.3048)
			(stroke
				(width 0.1)
				(type default)
			)
			(layer "F.Fab")
		)
		(fp_line
			(start 0.12065 -0.3048)
			(end 0.67945 -0.3048)
			(stroke
				(width 0.1)
				(type default)
			)
			(layer "F.Fab")
		)
		(fp_line
			(start 0.67945 -0.3048)
			(end 0.67945 0.3048)
			(stroke
				(width 0.1)
				(type default)
			)
			(layer "F.Fab")
		)
		(fp_line
			(start -0.67945 -0.305054)
			(end -0.12065 -0.305054)
			(stroke
				(width 0.1)
				(type default)
			)
			(layer "F.Fab")
		)
		(fp_line
			(start -0.12065 -0.305054)
			(end -0.12065 -0.2794)
			(stroke
				(width 0.1)
				(type default)
			)
			(layer "F.Fab")
		)
		(pad "1" smd circle
			(at -0.40005 0 270)
			(size 0 0)
			(layers "F.Cu" "F.Mask" "F.Paste")
			(net "P12V_AUX")
		)
		(pad "2" smd circle
			(at 0.40005 0 270)
			(size 0 0)
			(layers "F.Cu" "F.Mask" "F.Paste")
			(net "P12V_OCP_1_EN_G")
		)
	)
	(footprint ""
		(layer "F.Cu")
		(at 64.325754 -373.03583 -90)
		(property "Reference" "C814"
			(at 0 0 270)
			(layer "F.SilkS")
			(hide yes)
			(effects
				(font
					(size 1.27 1.27)
				)
			)
		)
		(property "Value" ""
			(at 0 0 270)
			(layer "F.Fab")
			(effects
				(font
					(size 1.27 1.27)
				)
			)
		)
		(duplicate_pad_numbers_are_jumpers no)
		(fp_line
			(start -0.299974 0.150114)
			(end -0.299974 -0.150114)
			(stroke
				(width 0.1)
				(type default)
			)
			(layer "F.Fab")
		)
		(fp_line
			(start 0.299974 0.150114)
			(end -0.299974 0.150114)
			(stroke
				(width 0.1)
				(type default)
			)
			(layer "F.Fab")
		)
		(fp_line
			(start -0.299974 -0.150114)
			(end 0.299974 -0.150114)
			(stroke
				(width 0.1)
				(type default)
			)
			(layer "F.Fab")
		)
		(fp_line
			(start 0.299974 -0.150114)
			(end 0.299974 0.150114)
			(stroke
				(width 0.1)
				(type default)
			)
			(layer "F.Fab")
		)
		(pad "1" smd rect
			(at -0.2667 0 270)
			(size 0.3048 0.381)
			(layers "F.Cu" "F.Mask" "F.Paste")
			(net "P5E_CPU1_P0_TX_C_DN<11>")
		)
		(pad "2" smd rect
			(at 0.2667 0 270)
			(size 0.3048 0.381)
			(layers "F.Cu" "F.Mask" "F.Paste")
			(net "P5E_CPU1_P0_TX_DN<11>")
		)
	)
	(footprint ""
		(layer "F.Cu")
		(at 220.363034 -75.02779 -90)
		(property "Reference" "PR3967"
			(at 0 0 270)
			(layer "F.SilkS")
			(hide yes)
			(effects
				(font
					(size 1.27 1.27)
				)
			)
		)
		(property "Value" ""
			(at 0 0 270)
			(layer "F.Fab")
			(effects
				(font
					(size 1.27 1.27)
				)
			)
		)
		(duplicate_pad_numbers_are_jumpers no)
		(fp_line
			(start -0.7874 0.4064)
			(end -0.7874 -0.4064)
			(stroke
				(width 0.1524)
				(type default)
			)
			(layer "F.SilkS")
		)
		(fp_line
			(start 0.7874 0.4064)
			(end -0.7874 0.4064)
			(stroke
				(width 0.1524)
				(type default)
			)
			(layer "F.SilkS")
		)
		(fp_line
			(start -0.7874 -0.4064)
			(end 0.7874 -0.4064)
			(stroke
				(width 0.1524)
				(type default)
			)
			(layer "F.SilkS")
		)
		(fp_line
			(start 0.7874 -0.4064)
			(end 0.7874 0.4064)
			(stroke
				(width 0.1524)
				(type default)
			)
			(layer "F.SilkS")
		)
		(fp_line
			(start -0.67945 0.3048)
			(end -0.67945 -0.305054)
			(stroke
				(width 0.1)
				(type default)
			)
			(layer "F.Fab")
		)
		(fp_line
			(start -0.12065 0.3048)
			(end -0.67945 0.3048)
			(stroke
				(width 0.1)
				(type default)
			)
			(layer "F.Fab")
		)
		(fp_line
			(start 0.120396 0.3048)
			(end 0.120396 0.2794)
			(stroke
				(width 0.1)
				(type default)
			)
			(layer "F.Fab")
		)
		(fp_line
			(start 0.67945 0.3048)
			(end 0.120396 0.3048)
			(stroke
				(width 0.1)
				(type default)
			)
			(layer "F.Fab")
		)
		(fp_line
			(start -0.12065 0.2794)
			(end -0.12065 0.3048)
			(stroke
				(width 0.1)
				(type default)
			)
			(layer "F.Fab")
		)
		(fp_line
			(start 0.120396 0.2794)
			(end -0.12065 0.2794)
			(stroke
				(width 0.1)
				(type default)
			)
			(layer "F.Fab")
		)
		(fp_line
			(start -0.12065 -0.2794)
			(end 0.12065 -0.2794)
			(stroke
				(width 0.1)
				(type default)
			)
			(layer "F.Fab")
		)
		(fp_line
			(start 0.12065 -0.2794)
			(end 0.12065 -0.3048)
			(stroke
				(width 0.1)
				(type default)
			)
			(layer "F.Fab")
		)
		(fp_line
			(start 0.12065 -0.3048)
			(end 0.67945 -0.3048)
			(stroke
				(width 0.1)
				(type default)
			)
			(layer "F.Fab")
		)
		(fp_line
			(start 0.67945 -0.3048)
			(end 0.67945 0.3048)
			(stroke
				(width 0.1)
				(type default)
			)
			(layer "F.Fab")
		)
		(fp_line
			(start -0.67945 -0.305054)
			(end -0.12065 -0.305054)
			(stroke
				(width 0.1)
				(type default)
			)
			(layer "F.Fab")
		)
		(fp_line
			(start -0.12065 -0.305054)
			(end -0.12065 -0.2794)
			(stroke
				(width 0.1)
				(type default)
			)
			(layer "F.Fab")
		)
		(pad "1" smd circle
			(at -0.40005 0 270)
			(size 0 0)
			(layers "F.Cu" "F.Mask" "F.Paste")
			(net "P3V3_AUX")
		)
		(pad "2" smd circle
			(at 0.40005 0 270)
			(size 0 0)
			(layers "F.Cu" "F.Mask" "F.Paste")
			(net "P3V3_E1S_VCC_0")
		)
	)
	(footprint ""
		(layer "F.Cu")
		(at 240.792 -281.7368 180)
		(property "Reference" "PC6504"
			(at 0 0 180)
			(layer "F.SilkS")
			(hide yes)
			(effects
				(font
					(size 1.27 1.27)
				)
			)
		)
		(property "Value" ""
			(at 0 0 180)
			(layer "F.Fab")
			(effects
				(font
					(size 1.27 1.27)
				)
			)
		)
		(duplicate_pad_numbers_are_jumpers no)
		(fp_line
			(start 1.524 0.762)
			(end -1.524 0.762)
			(stroke
				(width 0.1524)
				(type default)
			)
			(layer "F.SilkS")
		)
		(fp_line
			(start 1.524 -0.762)
			(end 1.524 0.762)
			(stroke
				(width 0.1524)
				(type default)
			)
			(layer "F.SilkS")
		)
		(fp_line
			(start -1.524 0.762)
			(end -1.524 -0.762)
			(stroke
				(width 0.1524)
				(type default)
			)
			(layer "F.SilkS")
		)
		(fp_line
			(start -1.524 -0.762)
			(end 1.524 -0.762)
			(stroke
				(width 0.1524)
				(type default)
			)
			(layer "F.SilkS")
		)
		(fp_line
			(start 1.1049 0.724916)
			(end 1.1049 -0.724916)
			(stroke
				(width 0.1)
				(type default)
			)
			(layer "F.Fab")
		)
		(fp_line
			(start 1.1049 -0.724916)
			(end -1.1049 -0.724916)
			(stroke
				(width 0.1)
				(type default)
			)
			(layer "F.Fab")
		)
		(fp_line
			(start -1.1049 0.724916)
			(end 1.1049 0.724916)
			(stroke
				(width 0.1)
				(type default)
			)
			(layer "F.Fab")
		)
		(fp_line
			(start -1.1049 -0.724916)
			(end -1.1049 0.724916)
			(stroke
				(width 0.1)
				(type default)
			)
			(layer "F.Fab")
		)
		(pad "1" smd rect
			(at -0.889 0)
			(size 1.016 1.27)
			(layers "F.Cu" "F.Mask" "F.Paste")
			(net "SW_P12V_AUX_P1V8_RETIMER_CPU0_FLT")
		)
		(pad "2" smd rect
			(at 0.889 0)
			(size 1.016 1.27)
			(layers "F.Cu" "F.Mask" "F.Paste")
			(net "GND")
		)
	)
	(footprint ""
		(layer "F.Cu")
		(at 205.232508 -124.801376)
		(property "Reference" "R2663"
			(at 0 0 0)
			(layer "F.SilkS")
			(hide yes)
			(effects
				(font
					(size 1.27 1.27)
				)
			)
		)
		(property "Value" ""
			(at 0 0 0)
			(layer "F.Fab")
			(effects
				(font
					(size 1.27 1.27)
				)
			)
		)
		(duplicate_pad_numbers_are_jumpers no)
		(fp_line
			(start -0.7874 -0.4064)
			(end 0.7874 -0.4064)
			(stroke
				(width 0.1524)
				(type default)
			)
			(layer "F.SilkS")
		)
		(fp_line
			(start -0.7874 0.4064)
			(end -0.7874 -0.4064)
			(stroke
				(width 0.1524)
				(type default)
			)
			(layer "F.SilkS")
		)
		(fp_line
			(start 0.7874 -0.4064)
			(end 0.7874 0.4064)
			(stroke
				(width 0.1524)
				(type default)
			)
			(layer "F.SilkS")
		)
		(fp_line
			(start 0.7874 0.4064)
			(end -0.7874 0.4064)
			(stroke
				(width 0.1524)
				(type default)
			)
			(layer "F.SilkS")
		)
		(fp_line
			(start -0.67945 -0.305054)
			(end -0.12065 -0.305054)
			(stroke
				(width 0.1)
				(type default)
			)
			(layer "F.Fab")
		)
		(fp_line
			(start -0.67945 0.3048)
			(end -0.67945 -0.305054)
			(stroke
				(width 0.1)
				(type default)
			)
			(layer "F.Fab")
		)
		(fp_line
			(start -0.12065 -0.305054)
			(end -0.12065 -0.2794)
			(stroke
				(width 0.1)
				(type default)
			)
			(layer "F.Fab")
		)
		(fp_line
			(start -0.12065 -0.2794)
			(end 0.12065 -0.2794)
			(stroke
				(width 0.1)
				(type default)
			)
			(layer "F.Fab")
		)
		(fp_line
			(start -0.12065 0.2794)
			(end -0.12065 0.3048)
			(stroke
				(width 0.1)
				(type default)
			)
			(layer "F.Fab")
		)
		(fp_line
			(start -0.12065 0.3048)
			(end -0.67945 0.3048)
			(stroke
				(width 0.1)
				(type default)
			)
			(layer "F.Fab")
		)
		(fp_line
			(start 0.120396 0.2794)
			(end -0.12065 0.2794)
			(stroke
				(width 0.1)
				(type default)
			)
			(layer "F.Fab")
		)
		(fp_line
			(start 0.120396 0.3048)
			(end 0.120396 0.2794)
			(stroke
				(width 0.1)
				(type default)
			)
			(layer "F.Fab")
		)
		(fp_line
			(start 0.12065 -0.3048)
			(end 0.67945 -0.3048)
			(stroke
				(width 0.1)
				(type default)
			)
			(layer "F.Fab")
		)
		(fp_line
			(start 0.12065 -0.2794)
			(end 0.12065 -0.3048)
			(stroke
				(width 0.1)
				(type default)
			)
			(layer "F.Fab")
		)
		(fp_line
			(start 0.67945 -0.3048)
			(end 0.67945 0.3048)
			(stroke
				(width 0.1)
				(type default)
			)
			(layer "F.Fab")
		)
		(fp_line
			(start 0.67945 0.3048)
			(end 0.120396 0.3048)
			(stroke
				(width 0.1)
				(type default)
			)
			(layer "F.Fab")
		)
		(pad "1" smd circle
			(at -0.40005 0)
			(size 0 0)
			(layers "F.Cu" "F.Mask" "F.Paste")
			(net "FM_SWB_PWRGD_ISO_R")
		)
		(pad "2" smd circle
			(at 0.40005 0)
			(size 0 0)
			(layers "F.Cu" "F.Mask" "F.Paste")
			(net "FM_SWB_PWRGD_ISO")
		)
	)
)
